# T6G (Grand Teton) — schematic netlist excerpt (pin names and nets, part order shuffled) for the footprints in the layout excerpt that follows; sources: Cadence DE-HDL packaged netlist, KiCad conversion of 04192023_DAF0TMB3IC0_F0TG_MB_C_brd_V02_OCP.brd

C861  Q_CAP_DIFFBUS  DIFF BUS_0.22UF 6.3V 20% X6S  pkg C0201  page 64 : \1\ = P5E_CPU0_P2_TX_C_DP<4> ; \2\ = P5E_CPU0_P2_TX_DP<4>
R3979  Q_RES  100K 1% CHIP  pkg 0402LF  page 146 : A = P3V3_AUX ; B = P3V3_E1S_PWRGD_0_R
R620  Q_RES  0 5% CHIP  pkg 0201LF  page 342 : A = CLK_100M_RETIMER_CPU1_P2_R_DN ; B = CLK_100M_RETIMER_CPU1_P2_DN

(kicad_pcb
	(version 20260206)
	(generator "pcbnew")
	(generator_version "10.0")
	(general
		(thickness 1.6)
		(legacy_teardrops no)
	)
	(paper "A4")
	(title_block
		(title "04192023_DAF0TMB3IC0_F0TG_MB_C_brd_V02_OCP.brd")
		(comment 1 "Grand Teton / footprints 4601-4603 of 8354")
	)
	(layers
		(0 "F.Cu" signal "TOP")
		(4 "In1.Cu" signal "GND")
		(6 "In2.Cu" signal "IN1")
		(8 "In3.Cu" signal "GND1")
		(10 "In4.Cu" signal "IN2")
		(12 "In5.Cu" signal "GND2")
		(14 "In6.Cu" signal "IN3")
		(16 "In7.Cu" signal "GND3")
		(18 "In8.Cu" signal "VCC")
		(20 "In9.Cu" signal "VCC1")
		(22 "In10.Cu" signal "GND4")
		(24 "In11.Cu" signal "IN4")
		(26 "In12.Cu" signal "GND5")
		(28 "In13.Cu" signal "IN5")
		(30 "In14.Cu" signal "GND6")
		(32 "In15.Cu" signal "IN6")
		(34 "In16.Cu" signal "GND7")
		(2 "B.Cu" signal "BOTTOM")
		(9 "F.Adhes" user "F.Adhesive")
		(11 "B.Adhes" user "B.Adhesive")
		(13 "F.Paste" user "Package Geometry/Pastemask Top")
		(15 "B.Paste" user "Package Geometry/Pastemask Bottom")
		(5 "F.SilkS" user "Ref Des/Silkscreen Top")
		(7 "B.SilkS" user "Ref Des/Silkscreen Bottom")
		(1 "F.Mask" user "Board Geometry/Soldermask Top")
		(3 "B.Mask" user "Board Geometry/Soldermask Bottom")
		(17 "Dwgs.User" user "User.Drawings")
		(19 "Cmts.User" user "User.Comments")
		(21 "Eco1.User" user "User.Eco1")
		(23 "Eco2.User" user "User.Eco2")
		(25 "Edge.Cuts" user "Board Geometry/Outline")
		(27 "Margin" user)
		(31 "F.CrtYd" user "Package Geometry/Place Bound Top")
		(29 "B.CrtYd" user "Package Geometry/Place Bound Bottom")
		(35 "F.Fab" user "Ref Des/Assembly Top")
		(33 "B.Fab" user "Ref Des/Assembly Bottom")
	)
	(footprint ""
		(layer "F.Cu")
		(at 142.155672 -386.951474)
		(property "Reference" "R620"
			(at 0 0 0)
			(layer "F.SilkS")
			(hide yes)
			(effects
				(font
					(size 1.27 1.27)
				)
			)
		)
		(property "Value" ""
			(at 0 0 0)
			(layer "F.Fab")
			(effects
				(font
					(size 1.27 1.27)
				)
			)
		)
		(duplicate_pad_numbers_are_jumpers no)
		(fp_line
			(start -0.32512 -0.175006)
			(end 0.32512 -0.175006)
			(stroke
				(width 0.1)
				(type default)
			)
			(layer "F.Fab")
		)
		(fp_line
			(start -0.32512 0.175006)
			(end -0.32512 -0.175006)
			(stroke
				(width 0.1)
				(type default)
			)
			(layer "F.Fab")
		)
		(fp_line
			(start 0.32512 -0.175006)
			(end 0.32512 0.175006)
			(stroke
				(width 0.1)
				(type default)
			)
			(layer "F.Fab")
		)
		(fp_line
			(start 0.32512 0.175006)
			(end -0.32512 0.175006)
			(stroke
				(width 0.1)
				(type default)
			)
			(layer "F.Fab")
		)
		(pad "1" smd rect
			(at -0.2667 0)
			(size 0.3048 0.381)
			(layers "F.Cu" "F.Mask" "F.Paste")
			(net "CLK_100M_RETIMER_CPU1_P2_R_DN")
		)
		(pad "2" smd rect
			(at 0.2667 0 180)
			(size 0.3048 0.381)
			(layers "F.Cu" "F.Mask" "F.Paste")
			(net "CLK_100M_RETIMER_CPU1_P2_DN")
		)
	)
	(footprint ""
		(layer "F.Cu")
		(at 403.72284 -383.88163 -90)
		(property "Reference" "C861"
			(at 0 0 270)
			(layer "F.SilkS")
			(hide yes)
			(effects
				(font
					(size 1.27 1.27)
				)
			)
		)
		(property "Value" ""
			(at 0 0 270)
			(layer "F.Fab")
			(effects
				(font
					(size 1.27 1.27)
				)
			)
		)
		(duplicate_pad_numbers_are_jumpers no)
		(fp_line
			(start -0.299974 0.150114)
			(end -0.299974 -0.150114)
			(stroke
				(width 0.1)
				(type default)
			)
			(layer "F.Fab")
		)
		(fp_line
			(start 0.299974 0.150114)
			(end -0.299974 0.150114)
			(stroke
				(width 0.1)
				(type default)
			)
			(layer "F.Fab")
		)
		(fp_line
			(start -0.299974 -0.150114)
			(end 0.299974 -0.150114)
			(stroke
				(width 0.1)
				(type default)
			)
			(layer "F.Fab")
		)
		(fp_line
			(start 0.299974 -0.150114)
			(end 0.299974 0.150114)
			(stroke
				(width 0.1)
				(type default)
			)
			(layer "F.Fab")
		)
		(pad "1" smd rect
			(at -0.2667 0 270)
			(size 0.3048 0.381)
			(layers "F.Cu" "F.Mask" "F.Paste")
			(net "P5E_CPU0_P2_TX_C_DP<4>")
		)
		(pad "2" smd rect
			(at 0.2667 0 270)
			(size 0.3048 0.381)
			(layers "F.Cu" "F.Mask" "F.Paste")
			(net "P5E_CPU0_P2_TX_DP<4>")
		)
	)
	(footprint ""
		(layer "F.Cu")
		(at 225.171762 -69.318378 -90)
		(property "Reference" "R3979"
			(at 0 0 270)
			(layer "F.SilkS")
			(hide yes)
			(effects
				(font
					(size 1.27 1.27)
				)
			)
		)
		(property "Value" ""
			(at 0 0 270)
			(layer "F.Fab")
			(effects
				(font
					(size 1.27 1.27)
				)
			)
		)
		(duplicate_pad_numbers_are_jumpers no)
		(fp_line
			(start -0.7874 0.4064)
			(end -0.7874 -0.4064)
			(stroke
				(width 0.1524)
				(type default)
			)
			(layer "F.SilkS")
		)
		(fp_line
			(start 0.7874 0.4064)
			(end -0.7874 0.4064)
			(stroke
				(width 0.1524)
				(type default)
			)
			(layer "F.SilkS")
		)
		(fp_line
			(start -0.7874 -0.4064)
			(end 0.7874 -0.4064)
			(stroke
				(width 0.1524)
				(type default)
			)
			(layer "F.SilkS")
		)
		(fp_line
			(start 0.7874 -0.4064)
			(end 0.7874 0.4064)
			(stroke
				(width 0.1524)
				(type default)
			)
			(layer "F.SilkS")
		)
		(fp_line
			(start -0.67945 0.3048)
			(end -0.67945 -0.305054)
			(stroke
				(width 0.1)
				(type default)
			)
			(layer "F.Fab")
		)
		(fp_line
			(start -0.12065 0.3048)
			(end -0.67945 0.3048)
			(stroke
				(width 0.1)
				(type default)
			)
			(layer "F.Fab")
		)
		(fp_line
			(start 0.120396 0.3048)
			(end 0.120396 0.2794)
			(stroke
				(width 0.1)
				(type default)
			)
			(layer "F.Fab")
		)
		(fp_line
			(start 0.67945 0.3048)
			(end 0.120396 0.3048)
			(stroke
				(width 0.1)
				(type default)
			)
			(layer "F.Fab")
		)
		(fp_line
			(start -0.12065 0.2794)
			(end -0.12065 0.3048)
			(stroke
				(width 0.1)
				(type default)
			)
			(layer "F.Fab")
		)
		(fp_line
			(start 0.120396 0.2794)
			(end -0.12065 0.2794)
			(stroke
				(width 0.1)
				(type default)
			)
			(layer "F.Fab")
		)
		(fp_line
			(start -0.12065 -0.2794)
			(end 0.12065 -0.2794)
			(stroke
				(width 0.1)
				(type default)
			)
			(layer "F.Fab")
		)
		(fp_line
			(start 0.12065 -0.2794)
			(end 0.12065 -0.3048)
			(stroke
				(width 0.1)
				(type default)
			)
			(layer "F.Fab")
		)
		(fp_line
			(start 0.12065 -0.3048)
			(end 0.67945 -0.3048)
			(stroke
				(width 0.1)
				(type default)
			)
			(layer "F.Fab")
		)
		(fp_line
			(start 0.67945 -0.3048)
			(end 0.67945 0.3048)
			(stroke
				(width 0.1)
				(type default)
			)
			(layer "F.Fab")
		)
		(fp_line
			(start -0.67945 -0.305054)
			(end -0.12065 -0.305054)
			(stroke
				(width 0.1)
				(type default)
			)
			(layer "F.Fab")
		)
		(fp_line
			(start -0.12065 -0.305054)
			(end -0.12065 -0.2794)
			(stroke
				(width 0.1)
				(type default)
			)
			(layer "F.Fab")
		)
		(pad "1" smd circle
			(at -0.40005 0 270)
			(size 0 0)
			(layers "F.Cu" "F.Mask" "F.Paste")
			(net "P3V3_AUX")
		)
		(pad "2" smd circle
			(at 0.40005 0 270)
			(size 0 0)
			(layers "F.Cu" "F.Mask" "F.Paste")
			(net "P3V3_E1S_PWRGD_0_R")
		)
	)
)
